(kicad_pcb
	(version 20260206)
	(generator "pcbnew")
	(generator_version "10.0")
	(general
		(thickness 1.6)
		(legacy_teardrops no)
	)
	(paper "A4")
	(title_block
		(title "baseboard — 13948-1b.1110WZS1818.brd")
		(comment 1 "Honey Badger (Wiwynn) / footprints 204-210 of 2523")
	)
	(layers
		(0 "F.Cu" signal "TOP")
		(4 "In1.Cu" signal "L2GND")
		(6 "In2.Cu" signal "L3")
		(8 "In3.Cu" signal "L4VCC")
		(10 "In4.Cu" signal "L5VCC")
		(12 "In5.Cu" signal "L6")
		(14 "In6.Cu" signal "L7GND")
		(2 "B.Cu" signal "BOTTOM")
		(9 "F.Adhes" user "F.Adhesive")
		(11 "B.Adhes" user "B.Adhesive")
		(13 "F.Paste" user "Package Geometry/Pastemask Top")
		(15 "B.Paste" user "Package Geometry/Pastemask Bottom")
		(5 "F.SilkS" user "Ref Des/Silkscreen Top")
		(7 "B.SilkS" user "Ref Des/Silkscreen Bottom")
		(1 "F.Mask" user "Board Geometry/Soldermask Top")
		(3 "B.Mask" user "Board Geometry/Soldermask Bottom")
		(17 "Dwgs.User" user "User.Drawings")
		(19 "Cmts.User" user "User.Comments")
		(21 "Eco1.User" user "User.Eco1")
		(23 "Eco2.User" user "User.Eco2")
		(25 "Edge.Cuts" user "Board Geometry/Outline")
		(27 "Margin" user)
		(31 "F.CrtYd" user "Package Geometry/Place Bound Top")
		(29 "B.CrtYd" user "Package Geometry/Place Bound Bottom")
		(35 "F.Fab" user "Ref Des/Assembly Top")
		(33 "B.Fab" user "Ref Des/Assembly Bottom")
	)
	(footprint ""
		(layer "F.Cu")
		(at 95.70847 -109.474 -90)
		(property "Reference" "SR744"
			(at 0 0 270)
			(layer "F.SilkS")
			(hide yes)
			(effects
				(font
					(size 1.27 1.27)
				)
			)
		)
		(property "Value" "2K2R2F-GP"
			(at 0.064008 -3.993896 270)
			(unlocked yes)
			(layer "F.Fab")
			(hide yes)
			(effects
				(font
					(size 1.016 1.016)
					(thickness 0.1524)
				)
			)
		)
		(property "Device Type" "R402H16"
			(at 0.064008 -5.517896 270)
			(unlocked yes)
			(layer "F.Fab")
			(hide yes)
			(effects
				(font
					(size 1.016 1.016)
					(thickness 0.1524)
				)
			)
		)
		(duplicate_pad_numbers_are_jumpers no)
		(fp_line
			(start -0.508 -0.9398)
			(end -0.508 0.9398)
			(stroke
				(width 0.1524)
				(type default)
			)
			(layer "F.SilkS")
		)
		(fp_line
			(start 0.508 -0.9398)
			(end -0.508 -0.9398)
			(stroke
				(width 0.1524)
				(type default)
			)
			(layer "F.SilkS")
		)
		(fp_rect
			(start -0.508 0.9398)
			(end 0.508 -0.9398)
			(stroke
				(width 0)
				(type default)
			)
			(fill no)
			(layer "F.CrtYd")
		)
		(fp_rect
			(start -0.508 0.9398)
			(end 0.508 -0.9398)
			(stroke
				(width 0)
				(type default)
			)
			(fill no)
			(layer "F.Fab")
		)
		(pad "1" smd custom
			(at 0 -0.4445 270)
			(size 0.1397 0.1397)
			(layers "F.Cu" "F.Mask" "F.Paste")
			(net "EXP_I2C_SCL_2")
			(options
				(clearance outline)
				(anchor circle)
			)
			(primitives
				(gr_poly
					(pts
						(arc
							(start -0.1778 -0.2794)
							(mid -0.249642 -0.249642)
							(end -0.2794 -0.1778)
						)
						(arc
							(start -0.2794 0.1778)
							(mid -0.249642 0.249642)
							(end -0.1778 0.2794)
						)
						(arc
							(start 0.1778 0.2794)
							(mid 0.249642 0.249642)
							(end 0.2794 0.1778)
						)
						(arc
							(start 0.2794 -0.1778)
							(mid 0.249642 -0.249642)
							(end 0.1778 -0.2794)
						)
					)
					(width 0)
					(fill yes)
				)
			)
		)
		(pad "2" smd custom
			(at 0 0.4445 270)
			(size 0.1397 0.1397)
			(layers "F.Cu" "F.Mask" "F.Paste")
			(net "P1V8_E")
			(options
				(clearance outline)
				(anchor circle)
			)
			(primitives
				(gr_poly
					(pts
						(arc
							(start -0.1778 -0.2794)
							(mid -0.249642 -0.249642)
							(end -0.2794 -0.1778)
						)
						(arc
							(start -0.2794 0.1778)
							(mid -0.249642 0.249642)
							(end -0.1778 0.2794)
						)
						(arc
							(start 0.1778 0.2794)
							(mid 0.249642 0.249642)
							(end 0.2794 0.1778)
						)
						(arc
							(start 0.2794 -0.1778)
							(mid 0.249642 -0.249642)
							(end 0.1778 -0.2794)
						)
					)
					(width 0)
					(fill yes)
				)
			)
		)
	)
	(footprint ""
		(layer "F.Cu")
		(at 89.662 -224.663 -90)
		(property "Reference" "SR310"
			(at 0 0 270)
			(layer "F.SilkS")
			(hide yes)
			(effects
				(font
					(size 1.27 1.27)
				)
			)
		)
		(property "Value" "0R2J-2-GP"
			(at 0.064008 -3.993896 270)
			(unlocked yes)
			(layer "F.Fab")
			(hide yes)
			(effects
				(font
					(size 1.016 1.016)
					(thickness 0.1524)
				)
			)
		)
		(property "Device Type" "R402H16"
			(at 0.064008 -5.517896 270)
			(unlocked yes)
			(layer "F.Fab")
			(hide yes)
			(effects
				(font
					(size 1.016 1.016)
					(thickness 0.1524)
				)
			)
		)
		(duplicate_pad_numbers_are_jumpers no)
		(fp_line
			(start -0.508 -0.9398)
			(end -0.508 0.9398)
			(stroke
				(width 0.1524)
				(type default)
			)
			(layer "F.SilkS")
		)
		(fp_line
			(start 0.508 -0.9398)
			(end -0.508 -0.9398)
			(stroke
				(width 0.1524)
				(type default)
			)
			(layer "F.SilkS")
		)
		(fp_rect
			(start -0.508 0.9398)
			(end 0.508 -0.9398)
			(stroke
				(width 0)
				(type default)
			)
			(fill no)
			(layer "F.CrtYd")
		)
		(fp_rect
			(start -0.508 0.9398)
			(end 0.508 -0.9398)
			(stroke
				(width 0)
				(type default)
			)
			(fill no)
			(layer "F.Fab")
		)
		(pad "1" smd custom
			(at 0 -0.4445 270)
			(size 0.1397 0.1397)
			(layers "F.Cu" "F.Mask" "F.Paste")
			(net "FAULT_SCL")
			(options
				(clearance outline)
				(anchor circle)
			)
			(primitives
				(gr_poly
					(pts
						(arc
							(start -0.1778 -0.2794)
							(mid -0.249642 -0.249642)
							(end -0.2794 -0.1778)
						)
						(arc
							(start -0.2794 0.1778)
							(mid -0.249642 0.249642)
							(end -0.1778 0.2794)
						)
						(arc
							(start 0.1778 0.2794)
							(mid 0.249642 0.249642)
							(end 0.2794 0.1778)
						)
						(arc
							(start 0.2794 -0.1778)
							(mid 0.249642 -0.249642)
							(end 0.1778 -0.2794)
						)
					)
					(width 0)
					(fill yes)
				)
			)
		)
		(pad "2" smd custom
			(at 0 0.4445 270)
			(size 0.1397 0.1397)
			(layers "F.Cu" "F.Mask" "F.Paste")
			(net "EXP_SCL_L_0")
			(options
				(clearance outline)
				(anchor circle)
			)
			(primitives
				(gr_poly
					(pts
						(arc
							(start -0.1778 -0.2794)
							(mid -0.249642 -0.249642)
							(end -0.2794 -0.1778)
						)
						(arc
							(start -0.2794 0.1778)
							(mid -0.249642 0.249642)
							(end -0.1778 0.2794)
						)
						(arc
							(start 0.1778 0.2794)
							(mid 0.249642 0.249642)
							(end 0.2794 0.1778)
						)
						(arc
							(start 0.2794 -0.1778)
							(mid 0.249642 -0.249642)
							(end 0.1778 -0.2794)
						)
					)
					(width 0)
					(fill yes)
				)
			)
		)
	)
	(footprint ""
		(layer "F.Cu")
		(at 217.805 -165.354)
		(property "Reference" "C84"
			(at 0 0 0)
			(layer "F.SilkS")
			(hide yes)
			(effects
				(font
					(size 1.27 1.27)
				)
			)
		)
		(property "Value" "SCD1U16V2KX-3GP"
			(at 1.1811 -2.7051 0)
			(unlocked yes)
			(layer "F.Fab")
			(hide yes)
			(effects
				(font
					(size 1.016 1.016)
					(thickness 0.1524)
				)
			)
		)
		(property "Device Type" "C402H22"
			(at 1.1811 -4.2291 0)
			(unlocked yes)
			(layer "F.Fab")
			(hide yes)
			(effects
				(font
					(size 1.016 1.016)
					(thickness 0.1524)
				)
			)
		)
		(duplicate_pad_numbers_are_jumpers no)
		(fp_rect
			(start -0.4318 0.9525)
			(end 0.4318 -0.9525)
			(stroke
				(width 0)
				(type default)
			)
			(fill no)
			(layer "F.CrtYd")
		)
		(fp_rect
			(start -0.4318 0.9525)
			(end 0.4318 -0.9525)
			(stroke
				(width 0)
				(type default)
			)
			(fill no)
			(layer "F.Fab")
		)
		(pad "1" smd custom
			(at 0 -0.4445)
			(size 0.1524 0.1524)
			(layers "F.Cu" "F.Mask" "F.Paste")
			(net "P3V3_STBY")
			(options
				(clearance outline)
				(anchor circle)
			)
			(primitives
				(gr_poly
					(pts
						(arc
							(start 0.3048 -0.2032)
							(mid 0.275042 -0.275042)
							(end 0.2032 -0.3048)
						)
						(arc
							(start -0.2032 -0.3048)
							(mid -0.275042 -0.275042)
							(end -0.3048 -0.2032)
						)
						(arc
							(start -0.3048 0.2032)
							(mid -0.275042 0.275042)
							(end -0.2032 0.3048)
						)
						(arc
							(start 0.2032 0.3048)
							(mid 0.275042 0.275042)
							(end 0.3048 0.2032)
						)
					)
					(width 0)
					(fill yes)
				)
			)
		)
		(pad "2" smd custom
			(at 0 0.4445)
			(size 0.1524 0.1524)
			(layers "F.Cu" "F.Mask" "F.Paste")
			(net "GND")
			(options
				(clearance outline)
				(anchor circle)
			)
			(primitives
				(gr_poly
					(pts
						(arc
							(start 0.3048 -0.2032)
							(mid 0.275042 -0.275042)
							(end 0.2032 -0.3048)
						)
						(arc
							(start -0.2032 -0.3048)
							(mid -0.275042 -0.275042)
							(end -0.3048 -0.2032)
						)
						(arc
							(start -0.3048 0.2032)
							(mid -0.275042 0.275042)
							(end -0.2032 0.3048)
						)
						(arc
							(start 0.2032 0.3048)
							(mid 0.275042 0.275042)
							(end 0.3048 0.2032)
						)
					)
					(width 0)
					(fill yes)
				)
			)
		)
	)
	(footprint ""
		(layer "F.Cu")
		(at 331.978 -92.202 90)
		(property "Reference" "PC36"
			(at 0 0 90)
			(layer "F.SilkS")
			(hide yes)
			(effects
				(font
					(size 1.27 1.27)
				)
			)
		)
		(property "Value" "SC22U6D3V3MX-1-GP"
			(at 0 -2.8194 90)
			(unlocked yes)
			(layer "F.Fab")
			(hide yes)
			(effects
				(font
					(size 1.016 1.016)
					(thickness 0.1524)
				)
			)
		)
		(property "Device Type" "C603H40"
			(at 0 -4.3434 90)
			(unlocked yes)
			(layer "F.Fab")
			(hide yes)
			(effects
				(font
					(size 1.016 1.016)
					(thickness 0.1524)
				)
			)
		)
		(duplicate_pad_numbers_are_jumpers no)
		(fp_line
			(start 0.508 0)
			(end -0.508 0)
			(stroke
				(width 0.2032)
				(type default)
			)
			(layer "F.SilkS")
		)
		(fp_rect
			(start -0.5842 1.3335)
			(end 0.5842 -1.3335)
			(stroke
				(width 0)
				(type default)
			)
			(fill no)
			(layer "F.CrtYd")
		)
		(fp_rect
			(start -0.5842 1.3335)
			(end 0.5842 -1.3335)
			(stroke
				(width 0)
				(type default)
			)
			(fill no)
			(layer "F.Fab")
		)
		(pad "1" smd custom
			(at 0 -0.762 90)
			(size 0.2159 0.2159)
			(layers "F.Cu" "F.Mask" "F.Paste")
			(net "P3V3_STBY")
			(options
				(clearance outline)
				(anchor circle)
			)
			(primitives
				(gr_poly
					(pts
						(arc
							(start -0.3302 -0.4318)
							(mid -0.402042 -0.402042)
							(end -0.4318 -0.3302)
						)
						(arc
							(start -0.4318 0.3302)
							(mid -0.402042 0.402042)
							(end -0.3302 0.4318)
						)
						(arc
							(start 0.3302 0.4318)
							(mid 0.402042 0.402042)
							(end 0.4318 0.3302)
						)
						(arc
							(start 0.4318 -0.3302)
							(mid 0.402042 -0.402042)
							(end 0.3302 -0.4318)
						)
					)
					(width 0)
					(fill yes)
				)
			)
		)
		(pad "2" smd custom
			(at 0 0.762 90)
			(size 0.2159 0.2159)
			(layers "F.Cu" "F.Mask" "F.Paste")
			(net "GND")
			(options
				(clearance outline)
				(anchor circle)
			)
			(primitives
				(gr_poly
					(pts
						(arc
							(start -0.3302 -0.4318)
							(mid -0.402042 -0.402042)
							(end -0.4318 -0.3302)
						)
						(arc
							(start -0.4318 0.3302)
							(mid -0.402042 0.402042)
							(end -0.3302 0.4318)
						)
						(arc
							(start 0.3302 0.4318)
							(mid 0.402042 0.402042)
							(end 0.4318 0.3302)
						)
						(arc
							(start 0.4318 -0.3302)
							(mid 0.402042 -0.402042)
							(end 0.3302 -0.4318)
						)
					)
					(width 0)
					(fill yes)
				)
			)
		)
	)
	(footprint ""
		(layer "F.Cu")
		(at 261.493 -31.115)
		(property "Reference" "PR40"
			(at 0 0 0)
			(layer "F.SilkS")
			(hide yes)
			(effects
				(font
					(size 1.27 1.27)
				)
			)
		)
		(property "Value" "0R2J-2-GP"
			(at 0.064008 -3.993896 0)
			(unlocked yes)
			(layer "F.Fab")
			(hide yes)
			(effects
				(font
					(size 1.016 1.016)
					(thickness 0.1524)
				)
			)
		)
		(property "Device Type" "R402H16"
			(at 0.064008 -5.517896 0)
			(unlocked yes)
			(layer "F.Fab")
			(hide yes)
			(effects
				(font
					(size 1.016 1.016)
					(thickness 0.1524)
				)
			)
		)
		(duplicate_pad_numbers_are_jumpers no)
		(fp_line
			(start -0.508 -0.9398)
			(end -0.508 0.9398)
			(stroke
				(width 0.1524)
				(type default)
			)
			(layer "F.SilkS")
		)
		(fp_line
			(start 0.508 -0.9398)
			(end -0.508 -0.9398)
			(stroke
				(width 0.1524)
				(type default)
			)
			(layer "F.SilkS")
		)
		(fp_rect
			(start -0.508 0.9398)
			(end 0.508 -0.9398)
			(stroke
				(width 0)
				(type default)
			)
			(fill no)
			(layer "F.CrtYd")
		)
		(fp_rect
			(start -0.508 0.9398)
			(end 0.508 -0.9398)
			(stroke
				(width 0)
				(type default)
			)
			(fill no)
			(layer "F.Fab")
		)
		(pad "1" smd custom
			(at 0 -0.4445)
			(size 0.1397 0.1397)
			(layers "F.Cu" "F.Mask" "F.Paste")
			(net "P1V8_STBY_EN")
			(options
				(clearance outline)
				(anchor circle)
			)
			(primitives
				(gr_poly
					(pts
						(arc
							(start -0.1778 -0.2794)
							(mid -0.249642 -0.249642)
							(end -0.2794 -0.1778)
						)
						(arc
							(start -0.2794 0.1778)
							(mid -0.249642 0.249642)
							(end -0.1778 0.2794)
						)
						(arc
							(start 0.1778 0.2794)
							(mid 0.249642 0.249642)
							(end 0.2794 0.1778)
						)
						(arc
							(start 0.2794 -0.1778)
							(mid 0.249642 -0.249642)
							(end 0.1778 -0.2794)
						)
					)
					(width 0)
					(fill yes)
				)
			)
		)
		(pad "2" smd custom
			(at 0 0.4445)
			(size 0.1397 0.1397)
			(layers "F.Cu" "F.Mask" "F.Paste")
			(net "P3V3_STBY_PG")
			(options
				(clearance outline)
				(anchor circle)
			)
			(primitives
				(gr_poly
					(pts
						(arc
							(start -0.1778 -0.2794)
							(mid -0.249642 -0.249642)
							(end -0.2794 -0.1778)
						)
						(arc
							(start -0.2794 0.1778)
							(mid -0.249642 0.249642)
							(end -0.1778 0.2794)
						)
						(arc
							(start 0.1778 0.2794)
							(mid 0.249642 0.249642)
							(end 0.2794 0.1778)
						)
						(arc
							(start 0.2794 -0.1778)
							(mid 0.249642 -0.249642)
							(end 0.1778 -0.2794)
						)
					)
					(width 0)
					(fill yes)
				)
			)
		)
	)
	(footprint ""
		(layer "F.Cu")
		(at 273.558 -63.246)
		(property "Reference" "R520"
			(at 0 0 0)
			(layer "F.SilkS")
			(hide yes)
			(effects
				(font
					(size 1.27 1.27)
				)
			)
		)
		(property "Value" "D008R2512F-GP"
			(at 0.0762 -11.4046 0)
			(unlocked yes)
			(layer "F.Fab")
			(hide yes)
			(effects
				(font
					(size 1.016 1.016)
					(thickness 0.1524)
				)
			)
		)
		(property "Device Type" "R2512H38"
			(at 0.0762 -13.1318 0)
			(unlocked yes)
			(layer "F.Fab")
			(hide yes)
			(effects
				(font
					(size 1.016 1.016)
					(thickness 0.1524)
				)
			)
		)
		(duplicate_pad_numbers_are_jumpers no)
		(fp_line
			(start -2.0574 -3.9878)
			(end -2.0574 3.9878)
			(stroke
				(width 0.1524)
				(type default)
			)
			(layer "F.SilkS")
		)
		(fp_line
			(start -2.0574 3.9878)
			(end 2.0574 3.9878)
			(stroke
				(width 0.1524)
				(type default)
			)
			(layer "F.SilkS")
		)
		(fp_line
			(start 2.0574 -3.9878)
			(end -2.0574 -3.9878)
			(stroke
				(width 0.1524)
				(type default)
			)
			(layer "F.SilkS")
		)
		(fp_line
			(start 2.0574 3.9878)
			(end 2.0574 -3.9878)
			(stroke
				(width 0.1524)
				(type default)
			)
			(layer "F.SilkS")
		)
		(fp_rect
			(start -2.1336 4.064)
			(end 2.1336 -4.064)
			(stroke
				(width 0)
				(type default)
			)
			(fill no)
			(layer "F.CrtYd")
		)
		(fp_rect
			(start -2.1336 4.064)
			(end 2.1336 -4.064)
			(stroke
				(width 0)
				(type default)
			)
			(fill no)
			(layer "F.Fab")
		)
		(pad "1" smd rect
			(at 0 -2.794)
			(size 3.5052 1.778)
			(layers "F.Cu" "F.Mask" "F.Paste")
			(net "P12V_PCIE")
		)
		(pad "2" smd rect
			(at 0 2.794)
			(size 3.5052 1.778)
			(layers "F.Cu" "F.Mask" "F.Paste")
			(net "VSENSE_HSC_MSB")
		)
	)
	(footprint ""
		(layer "F.Cu")
		(at 290.377372 -191.862456 180)
		(property "Reference" "R229"
			(at 0 0 180)
			(layer "F.SilkS")
			(hide yes)
			(effects
				(font
					(size 1.27 1.27)
				)
			)
		)
		(property "Value" "240R2F-1-GP"
			(at 0.064008 -3.993896 180)
			(unlocked yes)
			(layer "F.Fab")
			(hide yes)
			(effects
				(font
					(size 1.016 1.016)
					(thickness 0.1524)
				)
			)
		)
		(property "Device Type" "R402H16"
			(at 0.064008 -5.517896 180)
			(unlocked yes)
			(layer "F.Fab")
			(hide yes)
			(effects
				(font
					(size 1.016 1.016)
					(thickness 0.1524)
				)
			)
		)
		(duplicate_pad_numbers_are_jumpers no)
		(fp_line
			(start 0.508 -0.9398)
			(end -0.508 -0.9398)
			(stroke
				(width 0.1524)
				(type default)
			)
			(layer "F.SilkS")
		)
		(fp_line
			(start -0.508 -0.9398)
			(end -0.508 0.9398)
			(stroke
				(width 0.1524)
				(type default)
			)
			(layer "F.SilkS")
		)
		(fp_rect
			(start -0.508 0.9398)
			(end 0.508 -0.9398)
			(stroke
				(width 0)
				(type default)
			)
			(fill no)
			(layer "F.CrtYd")
		)
		(fp_rect
			(start -0.508 0.9398)
			(end 0.508 -0.9398)
			(stroke
				(width 0)
				(type default)
			)
			(fill no)
			(layer "F.Fab")
		)
		(pad "1" smd custom
			(at 0 -0.4445 180)
			(size 0.1397 0.1397)
			(layers "F.Cu" "F.Mask" "F.Paste")
			(net "GND")
			(options
				(clearance outline)
				(anchor circle)
			)
			(primitives
				(gr_poly
					(pts
						(arc
							(start -0.1778 -0.2794)
							(mid -0.249642 -0.249642)
							(end -0.2794 -0.1778)
						)
						(arc
							(start -0.2794 0.1778)
							(mid -0.249642 0.249642)
							(end -0.1778 0.2794)
						)
						(arc
							(start 0.1778 0.2794)
							(mid 0.249642 0.249642)
							(end 0.2794 0.1778)
						)
						(arc
							(start 0.2794 -0.1778)
							(mid 0.249642 -0.249642)
							(end 0.1778 -0.2794)
						)
					)
					(width 0)
					(fill yes)
				)
			)
		)
		(pad "2" smd custom
			(at 0 0.4445 180)
			(size 0.1397 0.1397)
			(layers "F.Cu" "F.Mask" "F.Paste")
			(net "PD_ZQ")
			(options
				(clearance outline)
				(anchor circle)
			)
			(primitives
				(gr_poly
					(pts
						(arc
							(start -0.1778 -0.2794)
							(mid -0.249642 -0.249642)
							(end -0.2794 -0.1778)
						)
						(arc
							(start -0.2794 0.1778)
							(mid -0.249642 0.249642)
							(end -0.1778 0.2794)
						)
						(arc
							(start 0.1778 0.2794)
							(mid 0.249642 0.249642)
							(end 0.2794 0.1778)
						)
						(arc
							(start 0.2794 -0.1778)
							(mid 0.249642 -0.249642)
							(end 0.1778 -0.2794)
						)
					)
					(width 0)
					(fill yes)
				)
			)
		)
	)
)
